# S9S_MB_2U (Grand Teton) — schematic netlist excerpt (pin names and nets, part order shuffled) for the footprints in the layout excerpt that follows; sources: Cadence DE-HDL packaged netlist, KiCad conversion of 03242023_DA0F0TMBIJ0_F0T_Motherboard_J_brd_V01_OCP.brd

R3133  Q_RES  1K 1% CHIP  pkg 0402LF  page 162 : A = P3V3_AUX ; B = OCP_V3_2_PRSNT0_R_N
H49  HOLE  EMPTY  pkg TH  page 311 : \1\ = GND
PC375  Q_CAP  1UF 16V 10% X6S  pkg C0402  page 297 : A = SW_P12V_PVCCINFAON_CPU1_FLT ; B = GND

(kicad_pcb
	(version 20260206)
	(generator "pcbnew")
	(generator_version "10.0")
	(general
		(thickness 1.6)
		(legacy_teardrops no)
	)
	(paper "A4")
	(title_block
		(title "03242023_DA0F0TMBIJ0_F0T_Motherboard_J_brd_V01_OCP.brd")
		(comment 1 "Grand Teton / footprints 2473-2475 of 6105")
	)
	(layers
		(0 "F.Cu" signal "TOP")
		(4 "In1.Cu" signal "GND")
		(6 "In2.Cu" signal "IN1")
		(8 "In3.Cu" signal "GND1")
		(10 "In4.Cu" signal "IN2")
		(12 "In5.Cu" signal "GND2")
		(14 "In6.Cu" signal "IN3")
		(16 "In7.Cu" signal "GND3")
		(18 "In8.Cu" signal "VCC")
		(20 "In9.Cu" signal "VCC1")
		(22 "In10.Cu" signal "GND4")
		(24 "In11.Cu" signal "IN4")
		(26 "In12.Cu" signal "GND5")
		(28 "In13.Cu" signal "IN5")
		(30 "In14.Cu" signal "GND6")
		(32 "In15.Cu" signal "IN6")
		(34 "In16.Cu" signal "GND7")
		(2 "B.Cu" signal "BOTTOM")
		(9 "F.Adhes" user "F.Adhesive")
		(11 "B.Adhes" user "B.Adhesive")
		(13 "F.Paste" user "Package Geometry/Pastemask Top")
		(15 "B.Paste" user "Package Geometry/Pastemask Bottom")
		(5 "F.SilkS" user "Ref Des/Silkscreen Top")
		(7 "B.SilkS" user "Ref Des/Silkscreen Bottom")
		(1 "F.Mask" user "Board Geometry/Soldermask Top")
		(3 "B.Mask" user "Board Geometry/Soldermask Bottom")
		(17 "Dwgs.User" user "User.Drawings")
		(19 "Cmts.User" user "User.Comments")
		(21 "Eco1.User" user "User.Eco1")
		(23 "Eco2.User" user "User.Eco2")
		(25 "Edge.Cuts" user "Board Geometry/Outline")
		(27 "Margin" user)
		(31 "F.CrtYd" user "Package Geometry/Place Bound Top")
		(29 "B.CrtYd" user "Package Geometry/Place Bound Bottom")
		(35 "F.Fab" user "Ref Des/Assembly Top")
		(33 "B.Fab" user "Ref Des/Assembly Bottom")
	)
	(footprint ""
		(layer "F.Cu")
		(at 54.811168 -168.683178)
		(property "Reference" "PC375"
			(at 0 0 0)
			(layer "F.SilkS")
			(hide yes)
			(effects
				(font
					(size 1.27 1.27)
				)
			)
		)
		(property "Value" ""
			(at 0 0 0)
			(layer "F.Fab")
			(effects
				(font
					(size 1.27 1.27)
				)
			)
		)
		(duplicate_pad_numbers_are_jumpers no)
		(fp_line
			(start -0.7874 -0.4064)
			(end 0.7874 -0.4064)
			(stroke
				(width 0.1524)
				(type default)
			)
			(layer "F.SilkS")
		)
		(fp_line
			(start -0.7874 0.4064)
			(end -0.7874 -0.4064)
			(stroke
				(width 0.1524)
				(type default)
			)
			(layer "F.SilkS")
		)
		(fp_line
			(start 0.7874 -0.4064)
			(end 0.7874 0.4064)
			(stroke
				(width 0.1524)
				(type default)
			)
			(layer "F.SilkS")
		)
		(fp_line
			(start 0.7874 0.4064)
			(end -0.7874 0.4064)
			(stroke
				(width 0.1524)
				(type default)
			)
			(layer "F.SilkS")
		)
		(fp_line
			(start -0.67945 -0.305054)
			(end -0.12065 -0.305054)
			(stroke
				(width 0.1)
				(type default)
			)
			(layer "F.Fab")
		)
		(fp_line
			(start -0.67945 0.3048)
			(end -0.67945 -0.305054)
			(stroke
				(width 0.1)
				(type default)
			)
			(layer "F.Fab")
		)
		(fp_line
			(start -0.12065 -0.305054)
			(end -0.12065 -0.2794)
			(stroke
				(width 0.1)
				(type default)
			)
			(layer "F.Fab")
		)
		(fp_line
			(start -0.12065 -0.2794)
			(end 0.12065 -0.2794)
			(stroke
				(width 0.1)
				(type default)
			)
			(layer "F.Fab")
		)
		(fp_line
			(start -0.12065 0.2794)
			(end -0.12065 0.3048)
			(stroke
				(width 0.1)
				(type default)
			)
			(layer "F.Fab")
		)
		(fp_line
			(start -0.12065 0.3048)
			(end -0.67945 0.3048)
			(stroke
				(width 0.1)
				(type default)
			)
			(layer "F.Fab")
		)
		(fp_line
			(start 0.120396 0.2794)
			(end -0.12065 0.2794)
			(stroke
				(width 0.1)
				(type default)
			)
			(layer "F.Fab")
		)
		(fp_line
			(start 0.120396 0.3048)
			(end 0.120396 0.2794)
			(stroke
				(width 0.1)
				(type default)
			)
			(layer "F.Fab")
		)
		(fp_line
			(start 0.12065 -0.3048)
			(end 0.67945 -0.3048)
			(stroke
				(width 0.1)
				(type default)
			)
			(layer "F.Fab")
		)
		(fp_line
			(start 0.12065 -0.2794)
			(end 0.12065 -0.3048)
			(stroke
				(width 0.1)
				(type default)
			)
			(layer "F.Fab")
		)
		(fp_line
			(start 0.67945 -0.3048)
			(end 0.67945 0.3048)
			(stroke
				(width 0.1)
				(type default)
			)
			(layer "F.Fab")
		)
		(fp_line
			(start 0.67945 0.3048)
			(end 0.120396 0.3048)
			(stroke
				(width 0.1)
				(type default)
			)
			(layer "F.Fab")
		)
		(pad "1" smd circle
			(at -0.40005 0)
			(size 0 0)
			(layers "F.Cu" "F.Mask" "F.Paste")
			(net "SW_P12V_PVCCINFAON_CPU1_FLT")
		)
		(pad "2" smd circle
			(at 0.40005 0)
			(size 0 0)
			(layers "F.Cu" "F.Mask" "F.Paste")
			(net "GND")
		)
	)
	(footprint ""
		(layer "F.Cu")
		(at 136.519158 -354.434902)
		(property "Reference" "H49"
			(at -2.63906 -5.052568 0)
			(unlocked yes)
			(layer "F.SilkS")
			(effects
				(font
					(size 0.7874 0.5842)
					(thickness 0.1524)
				)
				(justify left)
			)
		)
		(property "Value" ""
			(at 0 0 0)
			(layer "F.Fab")
			(effects
				(font
					(size 1.27 1.27)
				)
			)
		)
		(duplicate_pad_numbers_are_jumpers no)
		(pad "1" thru_hole circle
			(at 0 0)
			(size 8.001 8.001)
			(drill 3.2004)
			(layers "*.Cu" "*.Mask")
			(remove_unused_layers no)
			(net "GND")
			(clearance -2.1463)
			(padstack
				(mode front_inner_back)
				(layer "Inner"
					(shape circle)
					(size 5.0038 5.0038)
					(clearance -0.6477)
				)
				(layer "B.Cu"
					(shape circle)
					(size 8.001 8.001)
					(clearance -2.1463)
				)
			)
		)
	)
	(footprint ""
		(layer "F.Cu")
		(at 20.60956 -77.028548)
		(property "Reference" "R3133"
			(at 0 0 0)
			(layer "F.SilkS")
			(hide yes)
			(effects
				(font
					(size 1.27 1.27)
				)
			)
		)
		(property "Value" ""
			(at 0 0 0)
			(layer "F.Fab")
			(effects
				(font
					(size 1.27 1.27)
				)
			)
		)
		(duplicate_pad_numbers_are_jumpers no)
		(fp_line
			(start -0.7874 -0.4064)
			(end 0.7874 -0.4064)
			(stroke
				(width 0.1524)
				(type default)
			)
			(layer "F.SilkS")
		)
		(fp_line
			(start -0.7874 0.4064)
			(end -0.7874 -0.4064)
			(stroke
				(width 0.1524)
				(type default)
			)
			(layer "F.SilkS")
		)
		(fp_line
			(start 0.7874 -0.4064)
			(end 0.7874 0.4064)
			(stroke
				(width 0.1524)
				(type default)
			)
			(layer "F.SilkS")
		)
		(fp_line
			(start 0.7874 0.4064)
			(end -0.7874 0.4064)
			(stroke
				(width 0.1524)
				(type default)
			)
			(layer "F.SilkS")
		)
		(fp_line
			(start -0.67945 -0.305054)
			(end -0.12065 -0.305054)
			(stroke
				(width 0.1)
				(type default)
			)
			(layer "F.Fab")
		)
		(fp_line
			(start -0.67945 0.3048)
			(end -0.67945 -0.305054)
			(stroke
				(width 0.1)
				(type default)
			)
			(layer "F.Fab")
		)
		(fp_line
			(start -0.12065 -0.305054)
			(end -0.12065 -0.2794)
			(stroke
				(width 0.1)
				(type default)
			)
			(layer "F.Fab")
		)
		(fp_line
			(start -0.12065 -0.2794)
			(end 0.12065 -0.2794)
			(stroke
				(width 0.1)
				(type default)
			)
			(layer "F.Fab")
		)
		(fp_line
			(start -0.12065 0.2794)
			(end -0.12065 0.3048)
			(stroke
				(width 0.1)
				(type default)
			)
			(layer "F.Fab")
		)
		(fp_line
			(start -0.12065 0.3048)
			(end -0.67945 0.3048)
			(stroke
				(width 0.1)
				(type default)
			)
			(layer "F.Fab")
		)
		(fp_line
			(start 0.120396 0.2794)
			(end -0.12065 0.2794)
			(stroke
				(width 0.1)
				(type default)
			)
			(layer "F.Fab")
		)
		(fp_line
			(start 0.120396 0.3048)
			(end 0.120396 0.2794)
			(stroke
				(width 0.1)
				(type default)
			)
			(layer "F.Fab")
		)
		(fp_line
			(start 0.12065 -0.3048)
			(end 0.67945 -0.3048)
			(stroke
				(width 0.1)
				(type default)
			)
			(layer "F.Fab")
		)
		(fp_line
			(start 0.12065 -0.2794)
			(end 0.12065 -0.3048)
			(stroke
				(width 0.1)
				(type default)
			)
			(layer "F.Fab")
		)
		(fp_line
			(start 0.67945 -0.3048)
			(end 0.67945 0.3048)
			(stroke
				(width 0.1)
				(type default)
			)
			(layer "F.Fab")
		)
		(fp_line
			(start 0.67945 0.3048)
			(end 0.120396 0.3048)
			(stroke
				(width 0.1)
				(type default)
			)
			(layer "F.Fab")
		)
		(pad "1" smd circle
			(at -0.40005 0)
			(size 0 0)
			(layers "F.Cu" "F.Mask" "F.Paste")
			(net "P3V3_AUX")
		)
		(pad "2" smd circle
			(at 0.40005 0)
			(size 0 0)
			(layers "F.Cu" "F.Mask" "F.Paste")
			(net "OCP_V3_2_PRSNT0_R_N")
		)
	)
)
